(kicad_pcb
	(version 20260206)
	(generator "pcbnew")
	(generator_version "10.0")
	(general
		(thickness 1.6)
		(legacy_teardrops no)
	)
	(paper "A4")
	(title_block
		(title "v1-pdb — T6M_PDB_D_0927_0900.brd")
		(comment 1 "Open CloudServer (Microsoft) / footprint 313 of 321 (J8), pads 1-46 of 46")
	)
	(layers
		(0 "F.Cu" signal "TOP")
		(4 "In1.Cu" signal "GND")
		(6 "In2.Cu" signal "IN1")
		(8 "In3.Cu" signal "VCC")
		(10 "In4.Cu" signal "VCC1")
		(12 "In5.Cu" signal "IN2")
		(14 "In6.Cu" signal "GND1")
		(2 "B.Cu" signal "BOTTOM")
		(9 "F.Adhes" user "F.Adhesive")
		(11 "B.Adhes" user "B.Adhesive")
		(13 "F.Paste" user "Package Geometry/Pastemask Top")
		(15 "B.Paste" user "Package Geometry/Pastemask Bottom")
		(5 "F.SilkS" user "Ref Des/Silkscreen Top")
		(7 "B.SilkS" user "Ref Des/Silkscreen Bottom")
		(1 "F.Mask" user "Board Geometry/Soldermask Top")
		(3 "B.Mask" user "Board Geometry/Soldermask Bottom")
		(17 "Dwgs.User" user "User.Drawings")
		(19 "Cmts.User" user "User.Comments")
		(21 "Eco1.User" user "User.Eco1")
		(23 "Eco2.User" user "User.Eco2")
		(25 "Edge.Cuts" user "Board Geometry/Outline")
		(27 "Margin" user)
		(31 "F.CrtYd" user "Package Geometry/Place Bound Top")
		(29 "B.CrtYd" user "Package Geometry/Place Bound Bottom")
		(35 "F.Fab" user "Ref Des/Assembly Top")
		(33 "B.Fab" user "Ref Des/Assembly Bottom")
	)
	(footprint ""
		(layer "B.Cu")
		(at 44.03979 -52.71008 90)
		(property "Reference" "J8"
			(at 6.17982 -4.9149 0)
			(unlocked yes)
			(layer "B.SilkS")
			(effects
				(font
					(size 0.7874 0.5842)
					(thickness 0.1524)
				)
				(justify left mirror)
			)
		)
		(property "Value" ""
			(at 0 0 90)
			(layer "B.Fab")
			(effects
				(font
					(size 1.27 1.27)
				)
				(justify mirror)
			)
		)
		(duplicate_pad_numbers_are_jumpers no)
		(pad "" np_thru_hole circle
			(at -1.35001 -2.54)
			(size 2.5146 2.5146)
			(drill 2.5146)
			(layers "*.Cu" "*.Mask")
			(clearance 0.381)
			(thermal_gap 0.381)
		)
		(pad "" np_thru_hole circle
			(at 0 50.8)
			(size 2.5146 2.5146)
			(drill 2.5146)
			(layers "*.Cu" "*.Mask")
			(clearance 0.381)
			(thermal_gap 0.381)
		)
		(pad "P1" thru_hole rect
			(at 0 0)
			(size 1.1684 1.1684)
			(drill 0.762)
			(layers "*.Cu" "*.Mask")
			(remove_unused_layers no)
			(net "GND")
			(clearance 0.0508)
			(padstack
				(mode front_inner_back)
				(layer "Inner"
					(shape circle)
					(size 1.1684 1.1684)
					(clearance 0.0508)
				)
				(layer "B.Cu"
					(shape rect)
					(size 1.1684 1.1684)
					(thermal_gap 0.0508)
					(clearance 0.0508)
				)
			)
		)
		(pad "P2" thru_hole circle
			(at 0 2.54)
			(size 1.1684 1.1684)
			(drill 0.762)
			(layers "*.Cu" "*.Mask")
			(remove_unused_layers no)
			(net "GND")
			(clearance 0.0508)
			(thermal_gap 0.0508)
		)
		(pad "P3" thru_hole circle
			(at 0 5.08)
			(size 1.1684 1.1684)
			(drill 0.762)
			(layers "*.Cu" "*.Mask")
			(remove_unused_layers no)
			(net "GND")
			(clearance 0.0508)
			(thermal_gap 0.0508)
		)
		(pad "P4" thru_hole circle
			(at 0 7.62)
			(size 1.1684 1.1684)
			(drill 0.762)
			(layers "*.Cu" "*.Mask")
			(remove_unused_layers no)
			(net "GND")
			(clearance 0.0508)
			(thermal_gap 0.0508)
		)
		(pad "P5" thru_hole circle
			(at 0 10.16)
			(size 1.1684 1.1684)
			(drill 0.762)
			(layers "*.Cu" "*.Mask")
			(remove_unused_layers no)
			(net "GND")
			(clearance 0.0508)
			(thermal_gap 0.0508)
		)
		(pad "P6" thru_hole circle
			(at 0 12.7)
			(size 1.1684 1.1684)
			(drill 0.762)
			(layers "*.Cu" "*.Mask")
			(remove_unused_layers no)
			(net "GND")
			(clearance 0.0508)
			(thermal_gap 0.0508)
		)
		(pad "P7" thru_hole circle
			(at 0 15.24)
			(size 1.1684 1.1684)
			(drill 0.762)
			(layers "*.Cu" "*.Mask")
			(remove_unused_layers no)
			(net "GND")
			(clearance 0.0508)
			(thermal_gap 0.0508)
		)
		(pad "P8" thru_hole circle
			(at 0 17.78)
			(size 1.1684 1.1684)
			(drill 0.762)
			(layers "*.Cu" "*.Mask")
			(remove_unused_layers no)
			(net "GND")
			(clearance 0.0508)
			(thermal_gap 0.0508)
		)
		(pad "P9" thru_hole circle
			(at 0 20.32)
			(size 1.1684 1.1684)
			(drill 0.762)
			(layers "*.Cu" "*.Mask")
			(remove_unused_layers no)
			(net "P12V")
			(clearance 0.0508)
			(thermal_gap 0.0508)
		)
		(pad "P10" thru_hole circle
			(at 0 22.86)
			(size 1.1684 1.1684)
			(drill 0.762)
			(layers "*.Cu" "*.Mask")
			(remove_unused_layers no)
			(net "P12V")
			(clearance 0.0508)
			(thermal_gap 0.0508)
		)
		(pad "P11" thru_hole circle
			(at 0 25.4)
			(size 1.1684 1.1684)
			(drill 0.762)
			(layers "*.Cu" "*.Mask")
			(remove_unused_layers no)
			(net "P12V")
			(clearance 0.0508)
			(thermal_gap 0.0508)
		)
		(pad "P12" thru_hole circle
			(at 0 27.94)
			(size 1.1684 1.1684)
			(drill 0.762)
			(layers "*.Cu" "*.Mask")
			(remove_unused_layers no)
			(net "P12V")
			(clearance 0.0508)
			(thermal_gap 0.0508)
		)
		(pad "P13" thru_hole circle
			(at 0 30.48)
			(size 1.1684 1.1684)
			(drill 0.762)
			(layers "*.Cu" "*.Mask")
			(remove_unused_layers no)
			(net "P12V")
			(clearance 0.0508)
			(thermal_gap 0.0508)
		)
		(pad "P14" thru_hole circle
			(at 0 33.02)
			(size 1.1684 1.1684)
			(drill 0.762)
			(layers "*.Cu" "*.Mask")
			(remove_unused_layers no)
			(net "P12V")
			(clearance 0.0508)
			(thermal_gap 0.0508)
		)
		(pad "P15" thru_hole circle
			(at 0 35.56)
			(size 1.1684 1.1684)
			(drill 0.762)
			(layers "*.Cu" "*.Mask")
			(remove_unused_layers no)
			(net "P12V")
			(clearance 0.0508)
			(thermal_gap 0.0508)
		)
		(pad "P16" thru_hole circle
			(at 0 38.1)
			(size 1.1684 1.1684)
			(drill 0.762)
			(layers "*.Cu" "*.Mask")
			(remove_unused_layers no)
			(net "P12V")
			(clearance 0.0508)
			(thermal_gap 0.0508)
		)
		(pad "P17" thru_hole circle
			(at -2.70002 38.1)
			(size 1.1684 1.1684)
			(drill 0.762)
			(layers "*.Cu" "*.Mask")
			(remove_unused_layers no)
			(net "P12V")
			(clearance 0.0508)
			(thermal_gap 0.0508)
		)
		(pad "P18" thru_hole circle
			(at -2.70002 35.56)
			(size 1.1684 1.1684)
			(drill 0.762)
			(layers "*.Cu" "*.Mask")
			(remove_unused_layers no)
			(net "P12V")
			(clearance 0.0508)
			(thermal_gap 0.0508)
		)
		(pad "P19" thru_hole circle
			(at -2.70002 33.02)
			(size 1.1684 1.1684)
			(drill 0.762)
			(layers "*.Cu" "*.Mask")
			(remove_unused_layers no)
			(net "P12V")
			(clearance 0.0508)
			(thermal_gap 0.0508)
		)
		(pad "P20" thru_hole circle
			(at -2.70002 30.48)
			(size 1.1684 1.1684)
			(drill 0.762)
			(layers "*.Cu" "*.Mask")
			(remove_unused_layers no)
			(net "P12V")
			(clearance 0.0508)
			(thermal_gap 0.0508)
		)
		(pad "P21" thru_hole circle
			(at -2.70002 27.94)
			(size 1.1684 1.1684)
			(drill 0.762)
			(layers "*.Cu" "*.Mask")
			(remove_unused_layers no)
			(net "P12V")
			(clearance 0.0508)
			(thermal_gap 0.0508)
		)
		(pad "P22" thru_hole circle
			(at -2.70002 25.4)
			(size 1.1684 1.1684)
			(drill 0.762)
			(layers "*.Cu" "*.Mask")
			(remove_unused_layers no)
			(net "P12V")
			(clearance 0.0508)
			(thermal_gap 0.0508)
		)
		(pad "P23" thru_hole circle
			(at -2.70002 22.86)
			(size 1.1684 1.1684)
			(drill 0.762)
			(layers "*.Cu" "*.Mask")
			(remove_unused_layers no)
			(net "P12V")
			(clearance 0.0508)
			(thermal_gap 0.0508)
		)
		(pad "P24" thru_hole circle
			(at -2.70002 20.32)
			(size 1.1684 1.1684)
			(drill 0.762)
			(layers "*.Cu" "*.Mask")
			(remove_unused_layers no)
			(net "P12V")
			(clearance 0.0508)
			(thermal_gap 0.0508)
		)
		(pad "P25" thru_hole circle
			(at -2.70002 17.78)
			(size 1.1684 1.1684)
			(drill 0.762)
			(layers "*.Cu" "*.Mask")
			(remove_unused_layers no)
			(net "GND")
			(clearance 0.0508)
			(thermal_gap 0.0508)
		)
		(pad "P26" thru_hole circle
			(at -2.70002 15.24)
			(size 1.1684 1.1684)
			(drill 0.762)
			(layers "*.Cu" "*.Mask")
			(remove_unused_layers no)
			(net "GND")
			(clearance 0.0508)
			(thermal_gap 0.0508)
		)
		(pad "P27" thru_hole circle
			(at -2.70002 12.7)
			(size 1.1684 1.1684)
			(drill 0.762)
			(layers "*.Cu" "*.Mask")
			(remove_unused_layers no)
			(net "GND")
			(clearance 0.0508)
			(thermal_gap 0.0508)
		)
		(pad "P28" thru_hole circle
			(at -2.70002 10.16)
			(size 1.1684 1.1684)
			(drill 0.762)
			(layers "*.Cu" "*.Mask")
			(remove_unused_layers no)
			(net "GND")
			(clearance 0.0508)
			(thermal_gap 0.0508)
		)
		(pad "P29" thru_hole circle
			(at -2.70002 7.62)
			(size 1.1684 1.1684)
			(drill 0.762)
			(layers "*.Cu" "*.Mask")
			(remove_unused_layers no)
			(net "GND")
			(clearance 0.0508)
			(thermal_gap 0.0508)
		)
		(pad "P30" thru_hole circle
			(at -2.70002 5.08)
			(size 1.1684 1.1684)
			(drill 0.762)
			(layers "*.Cu" "*.Mask")
			(remove_unused_layers no)
			(net "GND")
			(clearance 0.0508)
			(thermal_gap 0.0508)
		)
		(pad "P31" thru_hole circle
			(at -2.70002 2.54)
			(size 1.1684 1.1684)
			(drill 0.762)
			(layers "*.Cu" "*.Mask")
			(remove_unused_layers no)
			(net "GND")
			(clearance 0.0508)
			(thermal_gap 0.0508)
		)
		(pad "P32" thru_hole circle
			(at -2.70002 0)
			(size 1.1684 1.1684)
			(drill 0.762)
			(layers "*.Cu" "*.Mask")
			(remove_unused_layers no)
			(net "GND")
			(clearance 0.0508)
			(thermal_gap 0.0508)
		)
		(pad "S1" thru_hole circle
			(at 0.55499 41.60012)
			(size 1.1684 1.1684)
			(drill 0.762)
			(layers "*.Cu" "*.Mask")
			(remove_unused_layers no)
			(net "T2_BLAD1_TXD")
			(clearance 0.0508)
			(thermal_gap 0.0508)
		)
		(pad "S2" thru_hole circle
			(at -0.71501 42.87012)
			(size 1.1684 1.1684)
			(drill 0.762)
			(layers "*.Cu" "*.Mask")
			(remove_unused_layers no)
			(net "T2_BLAD1_RXD")
			(clearance 0.0508)
			(thermal_gap 0.0508)
		)
		(pad "S3" thru_hole circle
			(at 0.55499 44.14012)
			(size 1.1684 1.1684)
			(drill 0.762)
			(layers "*.Cu" "*.Mask")
			(remove_unused_layers no)
			(net "T2_BLAD1_EN")
			(clearance 0.0508)
			(thermal_gap 0.0508)
		)
		(pad "S4" thru_hole circle
			(at -0.71501 45.41012)
			(size 1.1684 1.1684)
			(drill 0.762)
			(layers "*.Cu" "*.Mask")
			(remove_unused_layers no)
			(net "T2_BLAD2_EN")
			(clearance 0.0508)
			(thermal_gap 0.0508)
		)
		(pad "S5" thru_hole circle
			(at 0.55499 46.68012)
			(size 1.1684 1.1684)
			(drill 0.762)
			(layers "*.Cu" "*.Mask")
			(remove_unused_layers no)
			(net "T2_BLAD2_TXD")
			(clearance 0.0508)
			(thermal_gap 0.0508)
		)
		(pad "S6" thru_hole circle
			(at -0.71501 47.95012)
			(size 1.1684 1.1684)
			(drill 0.762)
			(layers "*.Cu" "*.Mask")
			(remove_unused_layers no)
			(net "T2_BLAD2_RXD")
			(clearance 0.0508)
			(thermal_gap 0.0508)
		)
		(pad "S7" thru_hole circle
			(at -3.25501 47.95012)
			(size 1.1684 1.1684)
			(drill 0.762)
			(layers "*.Cu" "*.Mask")
			(remove_unused_layers no)
			(net "T2_BLAD4_RXD")
			(clearance 0.0508)
			(thermal_gap 0.0508)
		)
		(pad "S8" thru_hole circle
			(at -1.98501 46.68012)
			(size 1.1684 1.1684)
			(drill 0.762)
			(layers "*.Cu" "*.Mask")
			(remove_unused_layers no)
			(net "T2_BLAD4_TXD")
			(clearance 0.0508)
			(thermal_gap 0.0508)
		)
		(pad "S9" thru_hole circle
			(at -3.25501 45.41012)
			(size 1.1684 1.1684)
			(drill 0.762)
			(layers "*.Cu" "*.Mask")
			(remove_unused_layers no)
			(net "T2_BLAD4_EN")
			(clearance 0.0508)
			(thermal_gap 0.0508)
		)
		(pad "S10" thru_hole circle
			(at -1.98501 44.14012)
			(size 1.1684 1.1684)
			(drill 0.762)
			(layers "*.Cu" "*.Mask")
			(remove_unused_layers no)
			(net "T2_BLAD3_EN")
			(clearance 0.0508)
			(thermal_gap 0.0508)
		)
		(pad "S11" thru_hole circle
			(at -3.25501 42.87012)
			(size 1.1684 1.1684)
			(drill 0.762)
			(layers "*.Cu" "*.Mask")
			(remove_unused_layers no)
			(net "T2_BLAD3_RXD")
			(clearance 0.0508)
			(thermal_gap 0.0508)
		)
		(pad "S12" thru_hole circle
			(at -1.98501 41.60012)
			(size 1.1684 1.1684)
			(drill 0.762)
			(layers "*.Cu" "*.Mask")
			(remove_unused_layers no)
			(net "T2_BLAD3_TXD")
			(clearance 0.0508)
			(thermal_gap 0.0508)
		)
	)
)
